# TIMECARD (Time Appliance Project (Time Card)) — schematic netlist excerpt (pin names and nets, part order shuffled) for the footprints in the layout excerpt that follows; sources: Cadence DE-HDL packaged netlist, KiCad conversion of R4006-B0001-02_R01.brd

C169  CAPACITOR  0.1UF 10V 10%  pkg SMC_0402R_H022  page 14 : \1\ = XP1R0V_FPGA_VCCINT ; \2\ = SG
R81  RESISTOR  33OHM 1%  pkg SMC_0402R_H016  page 21 : \1\ = R_MAC_UART_RX_FPGA_TX ; \2\ = DBG_UART_MAC_RX

(kicad_pcb
	(version 20260206)
	(generator "pcbnew")
	(generator_version "10.0")
	(general
		(thickness 1.6)
		(legacy_teardrops no)
	)
	(paper "A4")
	(title_block
		(title "timecard-production-celestica-r4006 — R4006-B0001-02_R01.brd")
		(comment 1 "Time Appliance Project (Time Card) / footprints 1081-1082 of 1113")
	)
	(layers
		(0 "F.Cu" signal "TOP")
		(4 "In1.Cu" signal "L02_GND1")
		(6 "In2.Cu" signal "L03_SIG1")
		(8 "In3.Cu" signal "L04_GND2")
		(10 "In4.Cu" signal "L05_VCC1")
		(12 "In5.Cu" signal "L06_VCC2")
		(14 "In6.Cu" signal "L07_GND3")
		(16 "In7.Cu" signal "L08_SIG2")
		(18 "In8.Cu" signal "L09_GND4")
		(2 "B.Cu" signal "BOTTOM")
		(9 "F.Adhes" user "F.Adhesive")
		(11 "B.Adhes" user "B.Adhesive")
		(13 "F.Paste" user "Package Geometry/Pastemask Top")
		(15 "B.Paste" user "Package Geometry/Pastemask Bottom")
		(5 "F.SilkS" user "Ref Des/Silkscreen Top")
		(7 "B.SilkS" user "Ref Des/Silkscreen Bottom")
		(1 "F.Mask" user "Board Geometry/Soldermask Top")
		(3 "B.Mask" user "Board Geometry/Soldermask Bottom")
		(17 "Dwgs.User" user "User.Drawings")
		(19 "Cmts.User" user "User.Comments")
		(21 "Eco1.User" user "User.Eco1")
		(23 "Eco2.User" user "User.Eco2")
		(25 "Edge.Cuts" user "Board Geometry/Outline")
		(27 "Margin" user)
		(31 "F.CrtYd" user "Package Geometry/Place Bound Top")
		(29 "B.CrtYd" user "Package Geometry/Place Bound Bottom")
		(35 "F.Fab" user "Ref Des/Assembly Top")
		(33 "B.Fab" user "Ref Des/Assembly Bottom")
	)
	(footprint ""
		(layer "B.Cu")
		(at 106.847132 -38.323012 90)
		(property "Reference" "C169"
			(at -1.269492 -41.509442 270)
			(unlocked yes)
			(layer "B.SilkS")
			(effects
				(font
					(size 0.635 0.4064)
					(thickness 0.1524)
				)
				(justify mirror)
			)
		)
		(property "Value" "VAL*"
			(at 0 3.718306 90)
			(unlocked yes)
			(layer "B.Fab")
			(hide yes)
			(effects
				(font
					(size 0.7874 0.5842)
					(thickness 0.127)
				)
				(justify mirror)
			)
		)
		(property "Device Type" "CAPACITOR-G105-0B104-CK,0.1UF,A"
			(at 0 1.432306 90)
			(unlocked yes)
			(layer "B.Fab")
			(hide yes)
			(effects
				(font
					(size 0.7874 0.5842)
					(thickness 0.127)
				)
				(justify mirror)
			)
		)
		(property "User Part Number" "PARTNUM*"
			(at 0 2.575306 90)
			(unlocked yes)
			(layer "Cmts.User")
			(hide yes)
			(effects
				(font
					(size 0.7874 0.5842)
					(thickness 0.127)
				)
				(justify mirror)
			)
		)
		(property "Tolerance" "TOL*"
			(at 0 4.861306 90)
			(unlocked yes)
			(layer "Cmts.User")
			(hide yes)
			(effects
				(font
					(size 0.7874 0.5842)
					(thickness 0.127)
				)
				(justify mirror)
			)
		)
		(duplicate_pad_numbers_are_jumpers no)
		(fp_line
			(start 0.970026 -0.4699)
			(end -0.970026 -0.4699)
			(stroke
				(width 0.1)
				(type default)
			)
			(layer "B.SilkS")
		)
		(fp_line
			(start -0.970026 -0.4699)
			(end -0.970026 0.4699)
			(stroke
				(width 0.1)
				(type default)
			)
			(layer "B.SilkS")
		)
		(fp_line
			(start 0.970026 0.4699)
			(end 0.970026 -0.4699)
			(stroke
				(width 0.1)
				(type default)
			)
			(layer "B.SilkS")
		)
		(fp_line
			(start -0.970026 0.4699)
			(end 0.970026 0.4699)
			(stroke
				(width 0.1)
				(type default)
			)
			(layer "B.SilkS")
		)
		(fp_poly
			(pts
				(xy 0.970026 0.4699) (xy -0.970026 0.4699) (xy -0.970026 -0.4699) (xy 0.970026 -0.4699)
			)
			(stroke
				(width 0)
				(type default)
			)
			(fill no)
			(layer "B.CrtYd")
		)
		(fp_line
			(start 0.508 -0.3048)
			(end -0.508 -0.3048)
			(stroke
				(width 0.1)
				(type default)
			)
			(layer "B.Fab")
		)
		(fp_line
			(start -0.508 -0.3048)
			(end -0.508 0.3048)
			(stroke
				(width 0.1)
				(type default)
			)
			(layer "B.Fab")
		)
		(fp_line
			(start 0.508 0.3048)
			(end 0.508 -0.3048)
			(stroke
				(width 0.1)
				(type default)
			)
			(layer "B.Fab")
		)
		(fp_line
			(start -0.508 0.3048)
			(end 0.508 0.3048)
			(stroke
				(width 0.1)
				(type default)
			)
			(layer "B.Fab")
		)
		(pad "1" smd circle
			(at 0.500126 0 270)
			(size 0.635 0.635)
			(layers "B.Cu" "B.Mask" "B.Paste")
			(net "XP1R0V_FPGA_VCCINT")
		)
		(pad "2" smd circle
			(at -0.500126 0 270)
			(size 0.635 0.635)
			(layers "B.Cu" "B.Mask" "B.Paste")
			(net "SG")
		)
	)
	(footprint ""
		(layer "B.Cu")
		(at 152.781 -66.421)
		(property "Reference" "R81"
			(at 0 -1.10363 0)
			(unlocked yes)
			(layer "B.SilkS")
			(effects
				(font
					(size 0.7874 0.5842)
					(thickness 0.1524)
				)
				(justify mirror)
			)
		)
		(property "Value" "VAL*"
			(at -0.02032 2.13233 0)
			(unlocked yes)
			(layer "B.Fab")
			(hide yes)
			(effects
				(font
					(size 0.7874 0.5842)
					(thickness 0.1524)
				)
				(justify mirror)
			)
		)
		(property "Device Type" "RESISTOR-G155-133R0-01,33OHM,1%"
			(at -0.008382 1.210564 0)
			(unlocked yes)
			(layer "B.Fab")
			(hide yes)
			(effects
				(font
					(size 0.7874 0.5842)
					(thickness 0.1524)
				)
				(justify mirror)
			)
		)
		(property "User Part Number" "PARTNUM*"
			(at -0.02032 4.024884 0)
			(unlocked yes)
			(layer "Cmts.User")
			(hide yes)
			(effects
				(font
					(size 0.7874 0.5842)
					(thickness 0.1524)
				)
				(justify mirror)
			)
		)
		(property "Tolerance" "TOL*"
			(at -0.044704 3.05435 0)
			(unlocked yes)
			(layer "Cmts.User")
			(hide yes)
			(effects
				(font
					(size 0.7874 0.5842)
					(thickness 0.1524)
				)
				(justify mirror)
			)
		)
		(duplicate_pad_numbers_are_jumpers no)
		(fp_line
			(start -1.143 -0.5588)
			(end 1.143 -0.5588)
			(stroke
				(width 0.1)
				(type default)
			)
			(layer "B.SilkS")
		)
		(fp_line
			(start -1.143 0.5588)
			(end -1.143 -0.5588)
			(stroke
				(width 0.1)
				(type default)
			)
			(layer "B.SilkS")
		)
		(fp_line
			(start 1.143 -0.5588)
			(end 1.143 0.5588)
			(stroke
				(width 0.1)
				(type default)
			)
			(layer "B.SilkS")
		)
		(fp_line
			(start 1.143 0.5588)
			(end -1.143 0.5588)
			(stroke
				(width 0.1)
				(type default)
			)
			(layer "B.SilkS")
		)
		(fp_rect
			(start 1.143 0.5588)
			(end -1.143 -0.5588)
			(stroke
				(width 0)
				(type default)
			)
			(fill no)
			(layer "B.CrtYd")
		)
		(fp_line
			(start -0.508 -0.3048)
			(end 0.508 -0.3048)
			(stroke
				(width 0.1)
				(type default)
			)
			(layer "B.Fab")
		)
		(fp_line
			(start -0.508 0.3048)
			(end -0.508 -0.3048)
			(stroke
				(width 0.1)
				(type default)
			)
			(layer "B.Fab")
		)
		(fp_line
			(start 0.508 -0.3048)
			(end 0.508 0.3048)
			(stroke
				(width 0.1)
				(type default)
			)
			(layer "B.Fab")
		)
		(fp_line
			(start 0.508 0.3048)
			(end -0.508 0.3048)
			(stroke
				(width 0.1)
				(type default)
			)
			(layer "B.Fab")
		)
		(pad "1" smd rect
			(at 0.5334 0 180)
			(size 0.7112 0.6096)
			(layers "B.Cu" "B.Mask" "B.Paste")
			(net "R_MAC_UART_RX_FPGA_TX")
		)
		(pad "2" smd rect
			(at -0.5334 0 180)
			(size 0.7112 0.6096)
			(layers "B.Cu" "B.Mask" "B.Paste")
			(net "DBG_UART_MAC_RX")
		)
		(zone
			(layer "B.Cu")
			(hatch none 0.5)
			(connect_pads
				(clearance 0)
			)
			(min_thickness 0.25)
			(keepout
				(tracks allowed)
				(vias not_allowed)
				(pads allowed)
				(copperpour not_allowed)
				(footprints allowed)
			)
			(placement
				(enabled no)
				(sheetname "")
			)
			(fill
				(thermal_gap 0.5)
				(thermal_bridge_width 0.5)
				(island_removal_mode 0)
			)
			(polygon
				(pts
					(xy 152.8572 -66.1162) (xy 152.8572 -66.7258) (xy 152.7048 -66.7258) (xy 152.7048 -66.1162)
				)
			)
		)
	)
)
